# S9S_MB_2U (Grand Teton) — schematic netlist excerpt (pin names and nets, part order shuffled) for the footprints in the layout excerpt that follows; sources: Cadence DE-HDL packaged netlist, KiCad conversion of 03242023_DA0F0TMBIJ0_F0T_Motherboard_J_brd_V01_OCP.brd

R575  Q_RES  49.9 1% CHIP  pkg 0402LF  page 206 : A = FM_PLD_CLKS_DEV_EN ; B = FM_DB2000_DEV_EN
C158  Q_CAP_DIFFBUS  DIFF BUS_0.22UF 6.3V 20% X6S  pkg C0201  page 178 : \1\ = DMI_CPU0_PCH_RX_C_DP<6> ; \2\ = DMI_CPU0_PCH_RX_DP<6>
C88  Q_CAP  10UF 16V 10% X6S  pkg C0805  page 108 : A = P12V_S3_AUX_CPU1_NVDIMM ; B = GND

(kicad_pcb
	(version 20260206)
	(generator "pcbnew")
	(generator_version "10.0")
	(general
		(thickness 1.6)
		(legacy_teardrops no)
	)
	(paper "A4")
	(title_block
		(title "03242023_DA0F0TMBIJ0_F0T_Motherboard_J_brd_V01_OCP.brd")
		(comment 1 "Grand Teton / footprints 6081-6083 of 6105")
	)
	(layers
		(0 "F.Cu" signal "TOP")
		(4 "In1.Cu" signal "GND")
		(6 "In2.Cu" signal "IN1")
		(8 "In3.Cu" signal "GND1")
		(10 "In4.Cu" signal "IN2")
		(12 "In5.Cu" signal "GND2")
		(14 "In6.Cu" signal "IN3")
		(16 "In7.Cu" signal "GND3")
		(18 "In8.Cu" signal "VCC")
		(20 "In9.Cu" signal "VCC1")
		(22 "In10.Cu" signal "GND4")
		(24 "In11.Cu" signal "IN4")
		(26 "In12.Cu" signal "GND5")
		(28 "In13.Cu" signal "IN5")
		(30 "In14.Cu" signal "GND6")
		(32 "In15.Cu" signal "IN6")
		(34 "In16.Cu" signal "GND7")
		(2 "B.Cu" signal "BOTTOM")
		(9 "F.Adhes" user "F.Adhesive")
		(11 "B.Adhes" user "B.Adhesive")
		(13 "F.Paste" user "Package Geometry/Pastemask Top")
		(15 "B.Paste" user "Package Geometry/Pastemask Bottom")
		(5 "F.SilkS" user "Ref Des/Silkscreen Top")
		(7 "B.SilkS" user "Ref Des/Silkscreen Bottom")
		(1 "F.Mask" user "Board Geometry/Soldermask Top")
		(3 "B.Mask" user "Board Geometry/Soldermask Bottom")
		(17 "Dwgs.User" user "User.Drawings")
		(19 "Cmts.User" user "User.Comments")
		(21 "Eco1.User" user "User.Eco1")
		(23 "Eco2.User" user "User.Eco2")
		(25 "Edge.Cuts" user "Board Geometry/Outline")
		(27 "Margin" user)
		(31 "F.CrtYd" user "Package Geometry/Place Bound Top")
		(29 "B.CrtYd" user "Package Geometry/Place Bound Bottom")
		(35 "F.Fab" user "Ref Des/Assembly Top")
		(33 "B.Fab" user "Ref Des/Assembly Bottom")
	)
	(footprint ""
		(layer "B.Cu")
		(at 234.889294 -132.470906 90)
		(property "Reference" "R575"
			(at 0 0 90)
			(layer "B.SilkS")
			(hide yes)
			(effects
				(font
					(size 1.27 1.27)
				)
				(justify mirror)
			)
		)
		(property "Value" ""
			(at 0 0 90)
			(layer "B.Fab")
			(effects
				(font
					(size 1.27 1.27)
				)
				(justify mirror)
			)
		)
		(duplicate_pad_numbers_are_jumpers no)
		(fp_line
			(start 0.7874 -0.4064)
			(end -0.7874 -0.4064)
			(stroke
				(width 0.1524)
				(type default)
			)
			(layer "B.SilkS")
		)
		(fp_line
			(start -0.7874 -0.4064)
			(end -0.7874 0.4064)
			(stroke
				(width 0.1524)
				(type default)
			)
			(layer "B.SilkS")
		)
		(fp_line
			(start 0.7874 0.4064)
			(end 0.7874 -0.4064)
			(stroke
				(width 0.1524)
				(type default)
			)
			(layer "B.SilkS")
		)
		(fp_line
			(start -0.7874 0.4064)
			(end 0.7874 0.4064)
			(stroke
				(width 0.1524)
				(type default)
			)
			(layer "B.SilkS")
		)
		(fp_line
			(start 0.67945 -0.305054)
			(end 0.12065 -0.305054)
			(stroke
				(width 0.1)
				(type default)
			)
			(layer "B.Fab")
		)
		(fp_line
			(start 0.12065 -0.305054)
			(end 0.12065 -0.2794)
			(stroke
				(width 0.1)
				(type default)
			)
			(layer "B.Fab")
		)
		(fp_line
			(start -0.12065 -0.3048)
			(end -0.67945 -0.3048)
			(stroke
				(width 0.1)
				(type default)
			)
			(layer "B.Fab")
		)
		(fp_line
			(start -0.67945 -0.3048)
			(end -0.67945 0.3048)
			(stroke
				(width 0.1)
				(type default)
			)
			(layer "B.Fab")
		)
		(fp_line
			(start 0.12065 -0.2794)
			(end -0.12065 -0.2794)
			(stroke
				(width 0.1)
				(type default)
			)
			(layer "B.Fab")
		)
		(fp_line
			(start -0.12065 -0.2794)
			(end -0.12065 -0.3048)
			(stroke
				(width 0.1)
				(type default)
			)
			(layer "B.Fab")
		)
		(fp_line
			(start 0.12065 0.2794)
			(end 0.12065 0.3048)
			(stroke
				(width 0.1)
				(type default)
			)
			(layer "B.Fab")
		)
		(fp_line
			(start -0.120396 0.2794)
			(end 0.12065 0.2794)
			(stroke
				(width 0.1)
				(type default)
			)
			(layer "B.Fab")
		)
		(fp_line
			(start 0.67945 0.3048)
			(end 0.67945 -0.305054)
			(stroke
				(width 0.1)
				(type default)
			)
			(layer "B.Fab")
		)
		(fp_line
			(start 0.12065 0.3048)
			(end 0.67945 0.3048)
			(stroke
				(width 0.1)
				(type default)
			)
			(layer "B.Fab")
		)
		(fp_line
			(start -0.120396 0.3048)
			(end -0.120396 0.2794)
			(stroke
				(width 0.1)
				(type default)
			)
			(layer "B.Fab")
		)
		(fp_line
			(start -0.67945 0.3048)
			(end -0.120396 0.3048)
			(stroke
				(width 0.1)
				(type default)
			)
			(layer "B.Fab")
		)
		(pad "1" smd circle
			(at 0.40005 0 270)
			(size 0 0)
			(layers "B.Cu" "B.Mask" "B.Paste")
			(net "FM_PLD_CLKS_DEV_EN")
		)
		(pad "2" smd circle
			(at -0.40005 0 270)
			(size 0 0)
			(layers "B.Cu" "B.Mask" "B.Paste")
			(net "FM_DB2000_DEV_EN")
		)
	)
	(footprint ""
		(layer "B.Cu")
		(at 345.794076 -59.029854 45)
		(property "Reference" "C158"
			(at 0 0 45)
			(layer "B.SilkS")
			(hide yes)
			(effects
				(font
					(size 1.27 1.27)
				)
				(justify mirror)
			)
		)
		(property "Value" ""
			(at 0 0 45)
			(layer "B.Fab")
			(effects
				(font
					(size 1.27 1.27)
				)
				(justify mirror)
			)
		)
		(duplicate_pad_numbers_are_jumpers no)
		(fp_line
			(start -0.299941 -0.15015)
			(end -0.299941 0.15015)
			(stroke
				(width 0.1)
				(type default)
			)
			(layer "B.Fab")
		)
		(fp_line
			(start -0.299941 0.15015)
			(end 0.299941 0.15015)
			(stroke
				(width 0.1)
				(type default)
			)
			(layer "B.Fab")
		)
		(fp_line
			(start 0.299941 -0.15015)
			(end -0.299941 -0.15015)
			(stroke
				(width 0.1)
				(type default)
			)
			(layer "B.Fab")
		)
		(fp_line
			(start 0.299941 0.15015)
			(end 0.299941 -0.15015)
			(stroke
				(width 0.1)
				(type default)
			)
			(layer "B.Fab")
		)
		(pad "1" smd rect
			(at 0.266699 0 225)
			(size 0.3048 0.381)
			(layers "B.Cu" "B.Mask" "B.Paste")
			(net "DMI_CPU0_PCH_RX_C_DP<6>")
		)
		(pad "2" smd rect
			(at -0.266699 0 225)
			(size 0.3048 0.381)
			(layers "B.Cu" "B.Mask" "B.Paste")
			(net "DMI_CPU0_PCH_RX_DP<6>")
		)
	)
	(footprint ""
		(layer "B.Cu")
		(at 181.457346 -321.554856 -90)
		(property "Reference" "C88"
			(at 0 0 90)
			(layer "B.SilkS")
			(hide yes)
			(effects
				(font
					(size 1.27 1.27)
				)
				(justify mirror)
			)
		)
		(property "Value" ""
			(at 0 0 90)
			(layer "B.Fab")
			(effects
				(font
					(size 1.27 1.27)
				)
				(justify mirror)
			)
		)
		(duplicate_pad_numbers_are_jumpers no)
		(fp_line
			(start -1.524 0.762)
			(end 1.524 0.762)
			(stroke
				(width 0.1524)
				(type default)
			)
			(layer "B.SilkS")
		)
		(fp_line
			(start 1.524 0.762)
			(end 1.524 -0.762)
			(stroke
				(width 0.1524)
				(type default)
			)
			(layer "B.SilkS")
		)
		(fp_line
			(start -1.524 -0.762)
			(end -1.524 0.762)
			(stroke
				(width 0.1524)
				(type default)
			)
			(layer "B.SilkS")
		)
		(fp_line
			(start 1.524 -0.762)
			(end -1.524 -0.762)
			(stroke
				(width 0.1524)
				(type default)
			)
			(layer "B.SilkS")
		)
		(fp_line
			(start -1.1049 0.724916)
			(end -1.1049 -0.724916)
			(stroke
				(width 0.1)
				(type default)
			)
			(layer "B.Fab")
		)
		(fp_line
			(start 1.1049 0.724916)
			(end -1.1049 0.724916)
			(stroke
				(width 0.1)
				(type default)
			)
			(layer "B.Fab")
		)
		(fp_line
			(start -1.1049 -0.724916)
			(end 1.1049 -0.724916)
			(stroke
				(width 0.1)
				(type default)
			)
			(layer "B.Fab")
		)
		(fp_line
			(start 1.1049 -0.724916)
			(end 1.1049 0.724916)
			(stroke
				(width 0.1)
				(type default)
			)
			(layer "B.Fab")
		)
		(pad "1" smd rect
			(at 0.889 0 270)
			(size 1.016 1.27)
			(layers "B.Cu" "B.Mask" "B.Paste")
			(net "P12V_S3_AUX_CPU1_NVDIMM")
		)
		(pad "2" smd rect
			(at -0.889 0 270)
			(size 1.016 1.27)
			(layers "B.Cu" "B.Mask" "B.Paste")
			(net "GND")
		)
	)
)
